(kicad_pcb
	(version 20260206)
	(generator "pcbnew")
	(generator_version "10.0")
	(general
		(thickness 1.6)
		(legacy_teardrops no)
	)
	(paper "A4")
	(title_block
		(title "Wiwynn_Tioga_Pass_MB.brd")
		(comment 1 "Tioga Pass / footprint 241 of 4770 (EU1C2), pads 1-42 of 49")
	)
	(layers
		(0 "F.Cu" signal "TOP")
		(4 "In1.Cu" signal "L2GND")
		(6 "In2.Cu" signal "L3")
		(8 "In3.Cu" signal "L4GND")
		(10 "In4.Cu" signal "L5")
		(12 "In5.Cu" signal "L6GND")
		(14 "In6.Cu" signal "L7VCC")
		(16 "In7.Cu" signal "L8VCC")
		(18 "In8.Cu" signal "L9GND")
		(20 "In9.Cu" signal "L10")
		(22 "In10.Cu" signal "L11GND")
		(24 "In11.Cu" signal "L12")
		(26 "In12.Cu" signal "L13GND")
		(2 "B.Cu" signal "BOTTOM")
		(9 "F.Adhes" user "F.Adhesive")
		(11 "B.Adhes" user "B.Adhesive")
		(13 "F.Paste" user "Package Geometry/Pastemask Top")
		(15 "B.Paste" user "Package Geometry/Pastemask Bottom")
		(5 "F.SilkS" user "Ref Des/Silkscreen Top")
		(7 "B.SilkS" user "Ref Des/Silkscreen Bottom")
		(1 "F.Mask" user "Board Geometry/Soldermask Top")
		(3 "B.Mask" user "Board Geometry/Soldermask Bottom")
		(17 "Dwgs.User" user "User.Drawings")
		(19 "Cmts.User" user "User.Comments")
		(21 "Eco1.User" user "User.Eco1")
		(23 "Eco2.User" user "User.Eco2")
		(25 "Edge.Cuts" user "Board Geometry/Outline")
		(27 "Margin" user)
		(31 "F.CrtYd" user "Package Geometry/Place Bound Top")
		(29 "B.CrtYd" user "Package Geometry/Place Bound Bottom")
		(35 "F.Fab" user "Ref Des/Assembly Top")
		(33 "B.Fab" user "Ref Des/Assembly Bottom")
	)
	(footprint ""
		(layer "F.Cu")
		(at 19.431 -92.456)
		(property "Reference" "EU1C2"
			(at -7.8232 -3.45313 0)
			(unlocked yes)
			(layer "F.SilkS")
			(effects
				(font
					(size 0.7874 0.5842)
					(thickness 0.1524)
				)
				(justify left)
			)
		)
		(property "Value" ""
			(at 0 0 0)
			(layer "F.Fab")
			(effects
				(font
					(size 1.27 1.27)
				)
			)
		)
		(duplicate_pad_numbers_are_jumpers no)
		(pad "1" smd custom
			(at -2.8956 -2.199894)
			(size 0.0508 0.0508)
			(layers "F.Cu" "F.Mask" "F.Paste")
			(net "VR_PVSA_CPU1_PWM")
			(options
				(clearance outline)
				(anchor circle)
			)
			(primitives
				(gr_poly
					(pts
						(arc
							(start 0.254 -0.1016)
							(mid 0.3556 0)
							(end 0.254 0.1016)
						)
						(xy -0.3556 0.1016) (xy -0.3556 -0.1016)
					)
					(width 0)
					(fill yes)
				)
			)
		)
		(pad "2" smd custom
			(at -2.8956 -1.800098)
			(size 0.0508 0.0508)
			(layers "F.Cu" "F.Mask" "F.Paste")
			(net "Net_277")
			(options
				(clearance outline)
				(anchor circle)
			)
			(primitives
				(gr_poly
					(pts
						(arc
							(start 0.254 -0.1016)
							(mid 0.3556 0)
							(end 0.254 0.1016)
						)
						(xy -0.3556 0.1016) (xy -0.3556 -0.1016)
					)
					(width 0)
					(fill yes)
				)
			)
		)
		(pad "3" smd custom
			(at -2.8956 -1.400048)
			(size 0.0508 0.0508)
			(layers "F.Cu" "F.Mask" "F.Paste")
			(net "VR_PVCCIN_CPU1_PWM5")
			(options
				(clearance outline)
				(anchor circle)
			)
			(primitives
				(gr_poly
					(pts
						(arc
							(start 0.254 -0.1016)
							(mid 0.3556 0)
							(end 0.254 0.1016)
						)
						(xy -0.3556 0.1016) (xy -0.3556 -0.1016)
					)
					(width 0)
					(fill yes)
				)
			)
		)
		(pad "4" smd custom
			(at -2.8956 -0.999998)
			(size 0.0508 0.0508)
			(layers "F.Cu" "F.Mask" "F.Paste")
			(net "VR_PVCCIN_CPU1_PWM4")
			(options
				(clearance outline)
				(anchor circle)
			)
			(primitives
				(gr_poly
					(pts
						(arc
							(start 0.254 -0.1016)
							(mid 0.3556 0)
							(end 0.254 0.1016)
						)
						(xy -0.3556 0.1016) (xy -0.3556 -0.1016)
					)
					(width 0)
					(fill yes)
				)
			)
		)
		(pad "5" smd custom
			(at -2.8956 -0.599948)
			(size 0.0508 0.0508)
			(layers "F.Cu" "F.Mask" "F.Paste")
			(net "VR_PVCCIN_CPU1_PWM3")
			(options
				(clearance outline)
				(anchor circle)
			)
			(primitives
				(gr_poly
					(pts
						(arc
							(start 0.254 -0.1016)
							(mid 0.3556 0)
							(end 0.254 0.1016)
						)
						(xy -0.3556 0.1016) (xy -0.3556 -0.1016)
					)
					(width 0)
					(fill yes)
				)
			)
		)
		(pad "6" smd custom
			(at -2.8956 -0.199898)
			(size 0.0508 0.0508)
			(layers "F.Cu" "F.Mask" "F.Paste")
			(net "VR_PVCCIN_CPU1_PWM2")
			(options
				(clearance outline)
				(anchor circle)
			)
			(primitives
				(gr_poly
					(pts
						(arc
							(start 0.254 -0.1016)
							(mid 0.3556 0)
							(end 0.254 0.1016)
						)
						(xy -0.3556 0.1016) (xy -0.3556 -0.1016)
					)
					(width 0)
					(fill yes)
				)
			)
		)
		(pad "7" smd custom
			(at -2.8956 0.199898)
			(size 0.0508 0.0508)
			(layers "F.Cu" "F.Mask" "F.Paste")
			(net "VR_PVCCIN_CPU1_PWM1")
			(options
				(clearance outline)
				(anchor circle)
			)
			(primitives
				(gr_poly
					(pts
						(arc
							(start 0.254 -0.1016)
							(mid 0.3556 0)
							(end 0.254 0.1016)
						)
						(xy -0.3556 0.1016) (xy -0.3556 -0.1016)
					)
					(width 0)
					(fill yes)
				)
			)
		)
		(pad "8" smd custom
			(at -2.8956 0.599948)
			(size 0.0508 0.0508)
			(layers "F.Cu" "F.Mask" "F.Paste")
			(net "SMB_VR_STBY_LVC3_SDA")
			(options
				(clearance outline)
				(anchor circle)
			)
			(primitives
				(gr_poly
					(pts
						(arc
							(start 0.254 -0.1016)
							(mid 0.3556 0)
							(end 0.254 0.1016)
						)
						(xy -0.3556 0.1016) (xy -0.3556 -0.1016)
					)
					(width 0)
					(fill yes)
				)
			)
		)
		(pad "9" smd custom
			(at -2.8956 0.999998)
			(size 0.0508 0.0508)
			(layers "F.Cu" "F.Mask" "F.Paste")
			(net "SMB_VR_STBY_LVC3_SCL")
			(options
				(clearance outline)
				(anchor circle)
			)
			(primitives
				(gr_poly
					(pts
						(arc
							(start 0.254 -0.1016)
							(mid 0.3556 0)
							(end 0.254 0.1016)
						)
						(xy -0.3556 0.1016) (xy -0.3556 -0.1016)
					)
					(width 0)
					(fill yes)
				)
			)
		)
		(pad "10" smd custom
			(at -2.8956 1.400048)
			(size 0.0508 0.0508)
			(layers "F.Cu" "F.Mask" "F.Paste")
			(net "Net_278")
			(options
				(clearance outline)
				(anchor circle)
			)
			(primitives
				(gr_poly
					(pts
						(arc
							(start 0.254 -0.1016)
							(mid 0.3556 0)
							(end 0.254 0.1016)
						)
						(xy -0.3556 0.1016) (xy -0.3556 -0.1016)
					)
					(width 0)
					(fill yes)
				)
			)
		)
		(pad "11" smd custom
			(at -2.8956 1.800098)
			(size 0.0508 0.0508)
			(layers "F.Cu" "F.Mask" "F.Paste")
			(net "VR_VRRDY_PVCCIN_CPU1")
			(options
				(clearance outline)
				(anchor circle)
			)
			(primitives
				(gr_poly
					(pts
						(arc
							(start 0.254 -0.1016)
							(mid 0.3556 0)
							(end 0.254 0.1016)
						)
						(xy -0.3556 0.1016) (xy -0.3556 -0.1016)
					)
					(width 0)
					(fill yes)
				)
			)
		)
		(pad "12" smd custom
			(at -2.8956 2.199894)
			(size 0.0508 0.0508)
			(layers "F.Cu" "F.Mask" "F.Paste")
			(net "VR_PVCCIN_CPU1_VREN")
			(options
				(clearance outline)
				(anchor circle)
			)
			(primitives
				(gr_poly
					(pts
						(arc
							(start 0.254 -0.1016)
							(mid 0.3556 0)
							(end 0.254 0.1016)
						)
						(xy -0.3556 0.1016) (xy -0.3556 -0.1016)
					)
					(width 0)
					(fill yes)
				)
			)
		)
		(pad "13" smd custom
			(at -2.199894 2.8956)
			(size 0.0508 0.0508)
			(layers "F.Cu" "F.Mask" "F.Paste")
			(net "IRQ_PVCCIN_CPU1_VRHOT_LVC3_R_N")
			(options
				(clearance outline)
				(anchor circle)
			)
			(primitives
				(gr_poly
					(pts
						(arc
							(start -0.1016 -0.254)
							(mid 0 -0.3556)
							(end 0.1016 -0.254)
						)
						(xy 0.1016 0.3556) (xy -0.1016 0.3556)
					)
					(width 0)
					(fill yes)
				)
			)
		)
		(pad "14" smd custom
			(at -1.800098 2.8956)
			(size 0.0508 0.0508)
			(layers "F.Cu" "F.Mask" "F.Paste")
			(net "FM_PVCCIN_CPU1_PWR_IN_ALERT_N")
			(options
				(clearance outline)
				(anchor circle)
			)
			(primitives
				(gr_poly
					(pts
						(arc
							(start -0.1016 -0.254)
							(mid 0 -0.3556)
							(end 0.1016 -0.254)
						)
						(xy 0.1016 0.3556) (xy -0.1016 0.3556)
					)
					(width 0)
					(fill yes)
				)
			)
		)
		(pad "15" smd custom
			(at -1.400048 2.8956)
			(size 0.0508 0.0508)
			(layers "F.Cu" "F.Mask" "F.Paste")
			(net "PWRGD_PVSA_CPU1_R")
			(options
				(clearance outline)
				(anchor circle)
			)
			(primitives
				(gr_poly
					(pts
						(arc
							(start -0.1016 -0.254)
							(mid 0 -0.3556)
							(end 0.1016 -0.254)
						)
						(xy 0.1016 0.3556) (xy -0.1016 0.3556)
					)
					(width 0)
					(fill yes)
				)
			)
		)
		(pad "16" smd custom
			(at -0.999998 2.8956)
			(size 0.0508 0.0508)
			(layers "F.Cu" "F.Mask" "F.Paste")
			(net "Net_220")
			(options
				(clearance outline)
				(anchor circle)
			)
			(primitives
				(gr_poly
					(pts
						(arc
							(start -0.1016 -0.254)
							(mid 0 -0.3556)
							(end 0.1016 -0.254)
						)
						(xy 0.1016 0.3556) (xy -0.1016 0.3556)
					)
					(width 0)
					(fill yes)
				)
			)
		)
		(pad "17" smd custom
			(at -0.599948 2.8956)
			(size 0.0508 0.0508)
			(layers "F.Cu" "F.Mask" "F.Paste")
			(net "SVID_VCLK_PVCCIN_CPU1")
			(options
				(clearance outline)
				(anchor circle)
			)
			(primitives
				(gr_poly
					(pts
						(arc
							(start -0.1016 -0.254)
							(mid 0 -0.3556)
							(end 0.1016 -0.254)
						)
						(xy 0.1016 0.3556) (xy -0.1016 0.3556)
					)
					(width 0)
					(fill yes)
				)
			)
		)
		(pad "18" smd custom
			(at -0.199898 2.8956)
			(size 0.0508 0.0508)
			(layers "F.Cu" "F.Mask" "F.Paste")
			(net "SVID_VDIO_PVCCIN_CPU1")
			(options
				(clearance outline)
				(anchor circle)
			)
			(primitives
				(gr_poly
					(pts
						(arc
							(start -0.1016 -0.254)
							(mid 0 -0.3556)
							(end 0.1016 -0.254)
						)
						(xy 0.1016 0.3556) (xy -0.1016 0.3556)
					)
					(width 0)
					(fill yes)
				)
			)
		)
		(pad "19" smd custom
			(at 0.199898 2.8956)
			(size 0.0508 0.0508)
			(layers "F.Cu" "F.Mask" "F.Paste")
			(net "SVID_VALERT_VCCIN_CPU1")
			(options
				(clearance outline)
				(anchor circle)
			)
			(primitives
				(gr_poly
					(pts
						(arc
							(start -0.1016 -0.254)
							(mid 0 -0.3556)
							(end 0.1016 -0.254)
						)
						(xy 0.1016 0.3556) (xy -0.1016 0.3556)
					)
					(width 0)
					(fill yes)
				)
			)
		)
		(pad "20" smd custom
			(at 0.599948 2.8956)
			(size 0.0508 0.0508)
			(layers "F.Cu" "F.Mask" "F.Paste")
			(net "PU_VR_PVCCIN_CPU1_FLT1_SMBALT_N")
			(options
				(clearance outline)
				(anchor circle)
			)
			(primitives
				(gr_poly
					(pts
						(arc
							(start -0.1016 -0.254)
							(mid 0 -0.3556)
							(end 0.1016 -0.254)
						)
						(xy 0.1016 0.3556) (xy -0.1016 0.3556)
					)
					(width 0)
					(fill yes)
				)
			)
		)
		(pad "21" smd custom
			(at 0.999998 2.8956)
			(size 0.0508 0.0508)
			(layers "F.Cu" "F.Mask" "F.Paste")
			(net "VSENSE_PVCCIN_CPU1_AVSP")
			(options
				(clearance outline)
				(anchor circle)
			)
			(primitives
				(gr_poly
					(pts
						(arc
							(start -0.1016 -0.254)
							(mid 0 -0.3556)
							(end 0.1016 -0.254)
						)
						(xy 0.1016 0.3556) (xy -0.1016 0.3556)
					)
					(width 0)
					(fill yes)
				)
			)
		)
		(pad "22" smd custom
			(at 1.400048 2.8956)
			(size 0.0508 0.0508)
			(layers "F.Cu" "F.Mask" "F.Paste")
			(net "VSENSE_PVCCIN_CPU1_N")
			(options
				(clearance outline)
				(anchor circle)
			)
			(primitives
				(gr_poly
					(pts
						(arc
							(start -0.1016 -0.254)
							(mid 0 -0.3556)
							(end 0.1016 -0.254)
						)
						(xy 0.1016 0.3556) (xy -0.1016 0.3556)
					)
					(width 0)
					(fill yes)
				)
			)
		)
		(pad "23" smd custom
			(at 1.800098 2.8956)
			(size 0.0508 0.0508)
			(layers "F.Cu" "F.Mask" "F.Paste")
			(net "VR_PVCCIN_CPU1_AIREF1")
			(options
				(clearance outline)
				(anchor circle)
			)
			(primitives
				(gr_poly
					(pts
						(arc
							(start -0.1016 -0.254)
							(mid 0 -0.3556)
							(end 0.1016 -0.254)
						)
						(xy 0.1016 0.3556) (xy -0.1016 0.3556)
					)
					(width 0)
					(fill yes)
				)
			)
		)
		(pad "24" smd custom
			(at 2.199894 2.8956)
			(size 0.0508 0.0508)
			(layers "F.Cu" "F.Mask" "F.Paste")
			(net "ISENSE_PVCCIN_CPU1_PH1_IMON")
			(options
				(clearance outline)
				(anchor circle)
			)
			(primitives
				(gr_poly
					(pts
						(arc
							(start -0.1016 -0.254)
							(mid 0 -0.3556)
							(end 0.1016 -0.254)
						)
						(xy 0.1016 0.3556) (xy -0.1016 0.3556)
					)
					(width 0)
					(fill yes)
				)
			)
		)
		(pad "25" smd custom
			(at 2.8956 2.199894)
			(size 0.0508 0.0508)
			(layers "F.Cu" "F.Mask" "F.Paste")
			(net "VR_PVCCIN_CPU1_AIREF2")
			(options
				(clearance outline)
				(anchor circle)
			)
			(primitives
				(gr_poly
					(pts
						(arc
							(start -0.254 0.1016)
							(mid -0.3556 0)
							(end -0.254 -0.1016)
						)
						(xy 0.3556 -0.1016) (xy 0.3556 0.1016)
					)
					(width 0)
					(fill yes)
				)
			)
		)
		(pad "26" smd custom
			(at 2.8956 1.800098)
			(size 0.0508 0.0508)
			(layers "F.Cu" "F.Mask" "F.Paste")
			(net "ISENSE_PVCCIN_CPU1_PH2_IMON")
			(options
				(clearance outline)
				(anchor circle)
			)
			(primitives
				(gr_poly
					(pts
						(arc
							(start -0.254 0.1016)
							(mid -0.3556 0)
							(end -0.254 -0.1016)
						)
						(xy 0.3556 -0.1016) (xy 0.3556 0.1016)
					)
					(width 0)
					(fill yes)
				)
			)
		)
		(pad "27" smd custom
			(at 2.8956 1.400048)
			(size 0.0508 0.0508)
			(layers "F.Cu" "F.Mask" "F.Paste")
			(net "VR_PVCCIN_CPU1_AIREF3")
			(options
				(clearance outline)
				(anchor circle)
			)
			(primitives
				(gr_poly
					(pts
						(arc
							(start -0.254 0.1016)
							(mid -0.3556 0)
							(end -0.254 -0.1016)
						)
						(xy 0.3556 -0.1016) (xy 0.3556 0.1016)
					)
					(width 0)
					(fill yes)
				)
			)
		)
		(pad "28" smd custom
			(at 2.8956 0.999998)
			(size 0.0508 0.0508)
			(layers "F.Cu" "F.Mask" "F.Paste")
			(net "ISENSE_PVCCIN_CPU1_PH3_IMON")
			(options
				(clearance outline)
				(anchor circle)
			)
			(primitives
				(gr_poly
					(pts
						(arc
							(start -0.254 0.1016)
							(mid -0.3556 0)
							(end -0.254 -0.1016)
						)
						(xy 0.3556 -0.1016) (xy 0.3556 0.1016)
					)
					(width 0)
					(fill yes)
				)
			)
		)
		(pad "29" smd custom
			(at 2.8956 0.599948)
			(size 0.0508 0.0508)
			(layers "F.Cu" "F.Mask" "F.Paste")
			(net "VR_PVCCIN_CPU1_AIREF4")
			(options
				(clearance outline)
				(anchor circle)
			)
			(primitives
				(gr_poly
					(pts
						(arc
							(start -0.254 0.1016)
							(mid -0.3556 0)
							(end -0.254 -0.1016)
						)
						(xy 0.3556 -0.1016) (xy 0.3556 0.1016)
					)
					(width 0)
					(fill yes)
				)
			)
		)
		(pad "30" smd custom
			(at 2.8956 0.199898)
			(size 0.0508 0.0508)
			(layers "F.Cu" "F.Mask" "F.Paste")
			(net "ISENSE_PVCCIN_CPU1_PH4_IMON")
			(options
				(clearance outline)
				(anchor circle)
			)
			(primitives
				(gr_poly
					(pts
						(arc
							(start -0.254 0.1016)
							(mid -0.3556 0)
							(end -0.254 -0.1016)
						)
						(xy 0.3556 -0.1016) (xy 0.3556 0.1016)
					)
					(width 0)
					(fill yes)
				)
			)
		)
		(pad "31" smd custom
			(at 2.8956 -0.199898)
			(size 0.0508 0.0508)
			(layers "F.Cu" "F.Mask" "F.Paste")
			(net "VR_PVCCIN_CPU1_AIREF5")
			(options
				(clearance outline)
				(anchor circle)
			)
			(primitives
				(gr_poly
					(pts
						(arc
							(start -0.254 0.1016)
							(mid -0.3556 0)
							(end -0.254 -0.1016)
						)
						(xy 0.3556 -0.1016) (xy 0.3556 0.1016)
					)
					(width 0)
					(fill yes)
				)
			)
		)
		(pad "32" smd custom
			(at 2.8956 -0.599948)
			(size 0.0508 0.0508)
			(layers "F.Cu" "F.Mask" "F.Paste")
			(net "ISENSE_PVCCIN_CPU1_PH5_IMON")
			(options
				(clearance outline)
				(anchor circle)
			)
			(primitives
				(gr_poly
					(pts
						(arc
							(start -0.254 0.1016)
							(mid -0.3556 0)
							(end -0.254 -0.1016)
						)
						(xy 0.3556 -0.1016) (xy 0.3556 0.1016)
					)
					(width 0)
					(fill yes)
				)
			)
		)
		(pad "33" smd custom
			(at 2.8956 -0.999998)
			(size 0.0508 0.0508)
			(layers "F.Cu" "F.Mask" "F.Paste")
			(net "Net_276")
			(options
				(clearance outline)
				(anchor circle)
			)
			(primitives
				(gr_poly
					(pts
						(arc
							(start -0.254 0.1016)
							(mid -0.3556 0)
							(end -0.254 -0.1016)
						)
						(xy 0.3556 -0.1016) (xy 0.3556 0.1016)
					)
					(width 0)
					(fill yes)
				)
			)
		)
		(pad "34" smd custom
			(at 2.8956 -1.400048)
			(size 0.0508 0.0508)
			(layers "F.Cu" "F.Mask" "F.Paste")
			(net "Net_291")
			(options
				(clearance outline)
				(anchor circle)
			)
			(primitives
				(gr_poly
					(pts
						(arc
							(start -0.254 0.1016)
							(mid -0.3556 0)
							(end -0.254 -0.1016)
						)
						(xy 0.3556 -0.1016) (xy 0.3556 0.1016)
					)
					(width 0)
					(fill yes)
				)
			)
		)
		(pad "35" smd custom
			(at 2.8956 -1.800098)
			(size 0.0508 0.0508)
			(layers "F.Cu" "F.Mask" "F.Paste")
			(net "VSENSE_PVSA_CPU1_BVSP")
			(options
				(clearance outline)
				(anchor circle)
			)
			(primitives
				(gr_poly
					(pts
						(arc
							(start -0.254 0.1016)
							(mid -0.3556 0)
							(end -0.254 -0.1016)
						)
						(xy 0.3556 -0.1016) (xy 0.3556 0.1016)
					)
					(width 0)
					(fill yes)
				)
			)
		)
		(pad "36" smd custom
			(at 2.8956 -2.199894)
			(size 0.0508 0.0508)
			(layers "F.Cu" "F.Mask" "F.Paste")
			(net "VSENSE_PVSA_CPU1_N")
			(options
				(clearance outline)
				(anchor circle)
			)
			(primitives
				(gr_poly
					(pts
						(arc
							(start -0.254 0.1016)
							(mid -0.3556 0)
							(end -0.254 -0.1016)
						)
						(xy 0.3556 -0.1016) (xy 0.3556 0.1016)
					)
					(width 0)
					(fill yes)
				)
			)
		)
		(pad "37" smd custom
			(at 2.199894 -2.8956)
			(size 0.0508 0.0508)
			(layers "F.Cu" "F.Mask" "F.Paste")
			(net "VR_PVSA_CPU1_BIREF1")
			(options
				(clearance outline)
				(anchor circle)
			)
			(primitives
				(gr_poly
					(pts
						(arc
							(start 0.1016 0.254)
							(mid 0 0.3556)
							(end -0.1016 0.254)
						)
						(xy -0.1016 -0.3556) (xy 0.1016 -0.3556)
					)
					(width 0)
					(fill yes)
				)
			)
		)
		(pad "38" smd custom
			(at 1.800098 -2.8956)
			(size 0.0508 0.0508)
			(layers "F.Cu" "F.Mask" "F.Paste")
			(net "ISENSE_PVSA_CPU1_IMON")
			(options
				(clearance outline)
				(anchor circle)
			)
			(primitives
				(gr_poly
					(pts
						(arc
							(start 0.1016 0.254)
							(mid 0 0.3556)
							(end -0.1016 0.254)
						)
						(xy -0.1016 -0.3556) (xy 0.1016 -0.3556)
					)
					(width 0)
					(fill yes)
				)
			)
		)
		(pad "39" smd custom
			(at 1.400048 -2.8956)
			(size 0.0508 0.0508)
			(layers "F.Cu" "F.Mask" "F.Paste")
			(net "PU_VR_PVCCIN_CPU1_IMON")
			(options
				(clearance outline)
				(anchor circle)
			)
			(primitives
				(gr_poly
					(pts
						(arc
							(start 0.1016 0.254)
							(mid 0 0.3556)
							(end -0.1016 0.254)
						)
						(xy -0.1016 -0.3556) (xy 0.1016 -0.3556)
					)
					(width 0)
					(fill yes)
				)
			)
		)
		(pad "40" smd custom
			(at 0.999998 -2.8956)
			(size 0.0508 0.0508)
			(layers "F.Cu" "F.Mask" "F.Paste")
			(net "Net_293")
			(options
				(clearance outline)
				(anchor circle)
			)
			(primitives
				(gr_poly
					(pts
						(arc
							(start 0.1016 0.254)
							(mid 0 0.3556)
							(end -0.1016 0.254)
						)
						(xy -0.1016 -0.3556) (xy 0.1016 -0.3556)
					)
					(width 0)
					(fill yes)
				)
			)
		)
		(pad "41" smd custom
			(at 0.599948 -2.8956)
			(size 0.0508 0.0508)
			(layers "F.Cu" "F.Mask" "F.Paste")
			(net "VR_PVCCIN_CPU1_XADDR2")
			(options
				(clearance outline)
				(anchor circle)
			)
			(primitives
				(gr_poly
					(pts
						(arc
							(start 0.1016 0.254)
							(mid 0 0.3556)
							(end -0.1016 0.254)
						)
						(xy -0.1016 -0.3556) (xy 0.1016 -0.3556)
					)
					(width 0)
					(fill yes)
				)
			)
		)
		(pad "42" smd custom
			(at 0.199898 -2.8956)
			(size 0.0508 0.0508)
			(layers "F.Cu" "F.Mask" "F.Paste")
			(net "A_TSENSE_PVSA_CPU1")
			(options
				(clearance outline)
				(anchor circle)
			)
			(primitives
				(gr_poly
					(pts
						(arc
							(start 0.1016 0.254)
							(mid 0 0.3556)
							(end -0.1016 0.254)
						)
						(xy -0.1016 -0.3556) (xy 0.1016 -0.3556)
					)
					(width 0)
					(fill yes)
				)
			)
		)
	)
)
